# T6G (Grand Teton) — schematic netlist excerpt (pin names and nets, part order shuffled) for the footprints in the layout excerpt that follows; sources: Cadence DE-HDL packaged netlist, KiCad conversion of 04192023_DAF0TMB3IC0_F0TG_MB_C_brd_V02_OCP.brd

R3191  Q_RES  33.2 1% CHIP  pkg 0402LF  page 139 : A = OCP_V3_2_PWRBRK_BUFF_N ; B = OCP_V3_2_PWRBRK_N
R6901  Q_RES  200 1% CHIP  pkg 0201LF  page 354 : A = RT_CPU1_P3_VQPS ; B = GND
C1993  Q_CAP_DIFFBUS  DIFF BUS_0.22UF 6.3V 20% X6S  pkg C0201  page 67 : \1\ = P3E_CPU0_P4_TX_C_DP<1> ; \2\ = P3E_CPU0_P4_TX_DP<1>

(kicad_pcb
	(version 20260206)
	(generator "pcbnew")
	(generator_version "10.0")
	(general
		(thickness 1.6)
		(legacy_teardrops no)
	)
	(paper "A4")
	(title_block
		(title "04192023_DAF0TMB3IC0_F0TG_MB_C_brd_V02_OCP.brd")
		(comment 1 "Grand Teton / footprints 186-188 of 8354")
	)
	(layers
		(0 "F.Cu" signal "TOP")
		(4 "In1.Cu" signal "GND")
		(6 "In2.Cu" signal "IN1")
		(8 "In3.Cu" signal "GND1")
		(10 "In4.Cu" signal "IN2")
		(12 "In5.Cu" signal "GND2")
		(14 "In6.Cu" signal "IN3")
		(16 "In7.Cu" signal "GND3")
		(18 "In8.Cu" signal "VCC")
		(20 "In9.Cu" signal "VCC1")
		(22 "In10.Cu" signal "GND4")
		(24 "In11.Cu" signal "IN4")
		(26 "In12.Cu" signal "GND5")
		(28 "In13.Cu" signal "IN5")
		(30 "In14.Cu" signal "GND6")
		(32 "In15.Cu" signal "IN6")
		(34 "In16.Cu" signal "GND7")
		(2 "B.Cu" signal "BOTTOM")
		(9 "F.Adhes" user "F.Adhesive")
		(11 "B.Adhes" user "B.Adhesive")
		(13 "F.Paste" user "Package Geometry/Pastemask Top")
		(15 "B.Paste" user "Package Geometry/Pastemask Bottom")
		(5 "F.SilkS" user "Ref Des/Silkscreen Top")
		(7 "B.SilkS" user "Ref Des/Silkscreen Bottom")
		(1 "F.Mask" user "Board Geometry/Soldermask Top")
		(3 "B.Mask" user "Board Geometry/Soldermask Bottom")
		(17 "Dwgs.User" user "User.Drawings")
		(19 "Cmts.User" user "User.Comments")
		(21 "Eco1.User" user "User.Eco1")
		(23 "Eco2.User" user "User.Eco2")
		(25 "Edge.Cuts" user "Board Geometry/Outline")
		(27 "Margin" user)
		(31 "F.CrtYd" user "Package Geometry/Place Bound Top")
		(29 "B.CrtYd" user "Package Geometry/Place Bound Bottom")
		(35 "F.Fab" user "Ref Des/Assembly Top")
		(33 "B.Fab" user "Ref Des/Assembly Bottom")
	)
	(footprint ""
		(layer "F.Cu")
		(at 257.951478 -106.909108)
		(property "Reference" "R3191"
			(at 0 0 0)
			(layer "F.SilkS")
			(hide yes)
			(effects
				(font
					(size 1.27 1.27)
				)
			)
		)
		(property "Value" ""
			(at 0 0 0)
			(layer "F.Fab")
			(effects
				(font
					(size 1.27 1.27)
				)
			)
		)
		(duplicate_pad_numbers_are_jumpers no)
		(fp_line
			(start -0.7874 -0.4064)
			(end 0.7874 -0.4064)
			(stroke
				(width 0.1524)
				(type default)
			)
			(layer "F.SilkS")
		)
		(fp_line
			(start -0.7874 0.4064)
			(end -0.7874 -0.4064)
			(stroke
				(width 0.1524)
				(type default)
			)
			(layer "F.SilkS")
		)
		(fp_line
			(start 0.7874 -0.4064)
			(end 0.7874 0.4064)
			(stroke
				(width 0.1524)
				(type default)
			)
			(layer "F.SilkS")
		)
		(fp_line
			(start 0.7874 0.4064)
			(end -0.7874 0.4064)
			(stroke
				(width 0.1524)
				(type default)
			)
			(layer "F.SilkS")
		)
		(fp_line
			(start -0.67945 -0.305054)
			(end -0.12065 -0.305054)
			(stroke
				(width 0.1)
				(type default)
			)
			(layer "F.Fab")
		)
		(fp_line
			(start -0.67945 0.3048)
			(end -0.67945 -0.305054)
			(stroke
				(width 0.1)
				(type default)
			)
			(layer "F.Fab")
		)
		(fp_line
			(start -0.12065 -0.305054)
			(end -0.12065 -0.2794)
			(stroke
				(width 0.1)
				(type default)
			)
			(layer "F.Fab")
		)
		(fp_line
			(start -0.12065 -0.2794)
			(end 0.12065 -0.2794)
			(stroke
				(width 0.1)
				(type default)
			)
			(layer "F.Fab")
		)
		(fp_line
			(start -0.12065 0.2794)
			(end -0.12065 0.3048)
			(stroke
				(width 0.1)
				(type default)
			)
			(layer "F.Fab")
		)
		(fp_line
			(start -0.12065 0.3048)
			(end -0.67945 0.3048)
			(stroke
				(width 0.1)
				(type default)
			)
			(layer "F.Fab")
		)
		(fp_line
			(start 0.120396 0.2794)
			(end -0.12065 0.2794)
			(stroke
				(width 0.1)
				(type default)
			)
			(layer "F.Fab")
		)
		(fp_line
			(start 0.120396 0.3048)
			(end 0.120396 0.2794)
			(stroke
				(width 0.1)
				(type default)
			)
			(layer "F.Fab")
		)
		(fp_line
			(start 0.12065 -0.3048)
			(end 0.67945 -0.3048)
			(stroke
				(width 0.1)
				(type default)
			)
			(layer "F.Fab")
		)
		(fp_line
			(start 0.12065 -0.2794)
			(end 0.12065 -0.3048)
			(stroke
				(width 0.1)
				(type default)
			)
			(layer "F.Fab")
		)
		(fp_line
			(start 0.67945 -0.3048)
			(end 0.67945 0.3048)
			(stroke
				(width 0.1)
				(type default)
			)
			(layer "F.Fab")
		)
		(fp_line
			(start 0.67945 0.3048)
			(end 0.120396 0.3048)
			(stroke
				(width 0.1)
				(type default)
			)
			(layer "F.Fab")
		)
		(pad "1" smd circle
			(at -0.40005 0)
			(size 0 0)
			(layers "F.Cu" "F.Mask" "F.Paste")
			(net "OCP_V3_2_PWRBRK_BUFF_N")
		)
		(pad "2" smd circle
			(at 0.40005 0)
			(size 0 0)
			(layers "F.Cu" "F.Mask" "F.Paste")
			(net "OCP_V3_2_PWRBRK_N")
		)
	)
	(footprint ""
		(layer "F.Cu")
		(at 239.152684 -53.821838)
		(property "Reference" "C1993"
			(at 0 0 0)
			(layer "F.SilkS")
			(hide yes)
			(effects
				(font
					(size 1.27 1.27)
				)
			)
		)
		(property "Value" ""
			(at 0 0 0)
			(layer "F.Fab")
			(effects
				(font
					(size 1.27 1.27)
				)
			)
		)
		(duplicate_pad_numbers_are_jumpers no)
		(fp_line
			(start -0.299974 -0.150114)
			(end 0.299974 -0.150114)
			(stroke
				(width 0.1)
				(type default)
			)
			(layer "F.Fab")
		)
		(fp_line
			(start -0.299974 0.150114)
			(end -0.299974 -0.150114)
			(stroke
				(width 0.1)
				(type default)
			)
			(layer "F.Fab")
		)
		(fp_line
			(start 0.299974 -0.150114)
			(end 0.299974 0.150114)
			(stroke
				(width 0.1)
				(type default)
			)
			(layer "F.Fab")
		)
		(fp_line
			(start 0.299974 0.150114)
			(end -0.299974 0.150114)
			(stroke
				(width 0.1)
				(type default)
			)
			(layer "F.Fab")
		)
		(pad "1" smd rect
			(at -0.2667 0)
			(size 0.3048 0.381)
			(layers "F.Cu" "F.Mask" "F.Paste")
			(net "P3E_CPU0_P4_TX_C_DP<1>")
		)
		(pad "2" smd rect
			(at 0.2667 0)
			(size 0.3048 0.381)
			(layers "F.Cu" "F.Mask" "F.Paste")
			(net "P3E_CPU0_P4_TX_DP<1>")
		)
	)
	(footprint ""
		(layer "F.Cu")
		(at 134.23138 -394.3477 -90)
		(property "Reference" "R6901"
			(at 0 0 270)
			(layer "F.SilkS")
			(hide yes)
			(effects
				(font
					(size 1.27 1.27)
				)
			)
		)
		(property "Value" ""
			(at 0 0 270)
			(layer "F.Fab")
			(effects
				(font
					(size 1.27 1.27)
				)
			)
		)
		(duplicate_pad_numbers_are_jumpers no)
		(fp_line
			(start -0.32512 0.175006)
			(end -0.32512 -0.175006)
			(stroke
				(width 0.1)
				(type default)
			)
			(layer "F.Fab")
		)
		(fp_line
			(start 0.32512 0.175006)
			(end -0.32512 0.175006)
			(stroke
				(width 0.1)
				(type default)
			)
			(layer "F.Fab")
		)
		(fp_line
			(start -0.32512 -0.175006)
			(end 0.32512 -0.175006)
			(stroke
				(width 0.1)
				(type default)
			)
			(layer "F.Fab")
		)
		(fp_line
			(start 0.32512 -0.175006)
			(end 0.32512 0.175006)
			(stroke
				(width 0.1)
				(type default)
			)
			(layer "F.Fab")
		)
		(pad "1" smd rect
			(at -0.2667 0 270)
			(size 0.3048 0.381)
			(layers "F.Cu" "F.Mask" "F.Paste")
			(net "RT_CPU1_P3_VQPS")
		)
		(pad "2" smd rect
			(at 0.2667 0 90)
			(size 0.3048 0.381)
			(layers "F.Cu" "F.Mask" "F.Paste")
			(net "GND")
		)
	)
)
